(kicad_pcb
	(version 20221018)
	(generator pcbnew)
	(general
    (thickness 1.6)
  )
	(paper "A4")
	(title_block
    (title "NUC Computer Cluster Power Breakout HW")
    (date "2023-10-18")
    (rev "1.4.3")
    (company "Antmicro Ltd.")
		(comment 9 "footprints 25-29 of 234")
	)
	(layers
    (0 "F.Cu" mixed)
    (1 "In1.Cu" power)
    (2 "In2.Cu" mixed)
    (31 "B.Cu" power)
    (32 "B.Adhes" user "B.Adhesive")
    (33 "F.Adhes" user "F.Adhesive")
    (34 "B.Paste" user)
    (35 "F.Paste" user)
    (36 "B.SilkS" user "B.Silkscreen")
    (37 "F.SilkS" user "F.Silkscreen")
    (38 "B.Mask" user)
    (39 "F.Mask" user)
    (40 "Dwgs.User" user "User.Drawings")
    (41 "Cmts.User" user "User.Comments")
    (42 "Eco1.User" user "User.Eco1")
    (43 "Eco2.User" user "User.Eco2")
    (44 "Edge.Cuts" user)
    (45 "Margin" user)
    (46 "B.CrtYd" user "B.Courtyard")
    (47 "F.CrtYd" user "F.Courtyard")
    (48 "B.Fab" user)
    (49 "F.Fab" user)
  )
	(footprint "antmicro-footprints:C_0402_1005Metric" (layer "F.Cu")
    (at 127.32 84.6 -90)
    (descr "Capacitor SMD 0402")
    (tags "capacitor SMD 0402")
    (property "Author" "Antmicro")
    (property "Dielectric" "X5R")
    (property "License" "Apache-2.0")
    (property "MPN" "GRM155R61H104KE14D")
    (property "Manufacturer" "Murata")
    (property "Sheetfile" "pow-cycl-curr-meas.kicad_sch")
    (property "Sheetname" "Power Cycling & Current Measurement")
    (property "Val" "100n")
    (property "Voltage" "50V")
    (property "ki_description" "SMD Multilayer Ceramic Capacitor, 0.1 µF, 50 V, 0402 [1005 Metric], ± 10%, X5R, GRM Series")
    (property "ki_keywords" "0402, SMT, CAPACITOR, PASSIVE, CERAMIC, MLCC")
    (attr smd)
    (fp_text reference "C30" (at 2 0.52 -90) (layer "F.SilkS")
        (effects (font (size 0.7 0.7) (thickness 0.15)) (justify left bottom))
    )
    (fp_text value "C_100n_0402" (at -1.022927 2.155213 -90) (layer "F.Fab")
        (effects (font (size 0.7 0.7) (thickness 0.15)) (justify left bottom))
    )
    (fp_text user "License: Apache-2.0" (at -0.939 5.799 -90) (layer "F.Fab") hide
        (effects (font (size 0.7 0.7) (thickness 0.15)) (justify left bottom))
    )
    (fp_text user "${REFERENCE}" (at -0.939 4.599 -90) (layer "F.Fab") hide
        (effects (font (size 0.7 0.7) (thickness 0.15)) (justify left bottom))
    )
    (fp_text user "Author: Antmicro" (at -0.939 3.399 -90) (layer "F.Fab") hide
        (effects (font (size 0.7 0.7) (thickness 0.15)) (justify left bottom))
    )
    (fp_rect (start -0.925 -0.47) (end 0.925 0.47)
      (stroke (width 0.05) (type default)) (fill none) (layer "F.CrtYd"))
    (fp_line (start -0.494 -0.25) (end 0.504 -0.25)
      (stroke (width 0.15) (type solid)) (layer "F.Fab"))
    (fp_line (start -0.494 0.248) (end -0.494 -0.25)
      (stroke (width 0.15) (type solid)) (layer "F.Fab"))
    (fp_line (start 0.504 -0.25) (end 0.504 0.248)
      (stroke (width 0.15) (type solid)) (layer "F.Fab"))
    (fp_line (start 0.504 0.248) (end -0.494 0.248)
      (stroke (width 0.15) (type solid)) (layer "F.Fab"))
    (pad "1" smd roundrect (at -0.48 0 270) (size 0.59 0.64) (layers "F.Cu" "F.Paste" "F.Mask") (roundrect_rratio 0.25)
      (net 1 "VCC3V3") (pintype "passive"))
    (pad "2" smd roundrect (at 0.48 0 270) (size 0.59 0.64) (layers "F.Cu" "F.Paste" "F.Mask") (roundrect_rratio 0.25)
      (net 4 "GND") (pintype "passive"))
  )
	(footprint "antmicro-footprints:R_0402_1005Metric" (layer "F.Cu")
    (at 171.25 96.5 -90)
    (descr "Resistor SMD 0402")
    (tags "resistor SMD 0402")
    (property "Author" "Antmicro")
    (property "Current" "1A")
    (property "License" "Apache-2.0")
    (property "MPN" "ERJ2GE0R00X")
    (property "Manufacturer" "Panasonic")
    (property "Sheetfile" "pow-cycl-curr-meas.kicad_sch")
    (property "Sheetname" "Power Cycling & Current Measurement")
    (property "Tolerance" "")
    (property "Val" "0R")
    (property "ki_description" "SMD Chip Resistor, Jumper, 0 ohm, 100 mW, 0402 [1005 Metric], Thick Film, General Purpose")
    (property "ki_keywords" "0402, SMT, RESISTOR, PASSIVE")
    (attr smd)
    (fp_text reference "R18" (at -0.85 -0.45 -90) (layer "F.SilkS")
        (effects (font (size 0.7 0.7) (thickness 0.15)) (justify left bottom))
    )
    (fp_text value "R_0R_0402" (at -1.011843 1.772047 -90) (layer "F.Fab")
        (effects (font (size 0.7 0.7) (thickness 0.15)) (justify left bottom))
    )
    (fp_text user "License: Apache-2.0" (at -0.95 5.169 -90) (layer "F.Fab") hide
        (effects (font (size 0.7 0.7) (thickness 0.15)) (justify left bottom))
    )
    (fp_text user "${REFERENCE}" (at -0.95 3.168 -90) (layer "F.Fab") hide
        (effects (font (size 0.7 0.7) (thickness 0.15)) (justify left bottom))
    )
    (fp_text user "Author: Antmicro" (at -0.95 4.169 -90) (layer "F.Fab") hide
        (effects (font (size 0.7 0.7) (thickness 0.15)) (justify left bottom))
    )
    (fp_rect (start -0.925 -0.47) (end 0.925 0.47)
      (stroke (width 0.05) (type default)) (fill none) (layer "F.CrtYd"))
    (fp_rect (start -0.5 -0.25) (end 0.5 0.25)
      (stroke (width 0.15) (type solid)) (fill none) (layer "F.Fab"))
    (pad "1" smd roundrect (at -0.48 0 270) (size 0.59 0.64) (layers "F.Cu" "F.Paste" "F.Mask") (roundrect_rratio 0.25)
      (net 107 "Net-(U10-A2)") (pintype "passive"))
    (pad "2" smd roundrect (at 0.48 0 270) (size 0.59 0.64) (layers "F.Cu" "F.Paste" "F.Mask") (roundrect_rratio 0.25)
      (net 4 "GND") (pintype "passive"))
  )
	(footprint "antmicro-footprints:SOIC-8_3.9x4.9x1.75mm_P1.27mm" (layer "F.Cu")
    (at 148.2775 82.1775 180)
    (property "Author" "Antmicro")
    (property "License" "Apache-2.0")
    (property "MPN" "TMCS1100A2QDRQ1")
    (property "Manufacturer" "Texas Instruments")
    (property "Sheetfile" "pow-cycl-curr-meas.kicad_sch")
    (property "Sheetname" "Power Cycling & Current Measurement")
    (property "ki_description" "Hall current Sensor/transducer")
    (property "ki_keywords" "SMT, SENSOR, IC, POWER")
    (attr smd)
    (fp_text reference "U11" (at 1.4275 2.8275) (layer "F.SilkS")
        (effects (font (size 0.7 0.7) (thickness 0.15)) (justify right bottom))
    )
    (fp_text value "TMCS1100A2-Q1" (at 0 3.65) (layer "F.Fab")
        (effects (font (size 0.7 0.7) (thickness 0.15)) (justify right bottom))
    )
    (fp_text user "${REFERENCE}" (at -3.476 7.099) (layer "F.Fab") hide
        (effects (font (size 0.7 0.7) (thickness 0.15)) (justify right bottom))
    )
    (fp_text user "License: Apache-2.0" (at -3.476 5.099) (layer "F.Fab") hide
        (effects (font (size 0.7 0.7) (thickness 0.15)) (justify right bottom))
    )
    (fp_text user "Author: Antmicro" (at -3.476 6.099) (layer "F.Fab") hide
        (effects (font (size 0.7 0.7) (thickness 0.15)) (justify right bottom))
    )
    (fp_line (start -1.95 -2.452) (end 1.95 -2.45)
      (stroke (width 0.15) (type solid)) (layer "F.SilkS"))
    (fp_line (start -1.95 2.45) (end 1.95 2.45)
      (stroke (width 0.15) (type solid)) (layer "F.SilkS"))
    (fp_circle (center -2.4 -2.45) (end -2.35 -2.4)
      (stroke (width 0.15) (type solid)) (fill solid) (layer "F.SilkS"))
    (fp_rect (start -3.625 -2.7) (end 3.625 2.7)
      (stroke (width 0.05) (type solid)) (fill none) (layer "F.CrtYd"))
    (fp_line (start -1.95 -1.18) (end -0.683 -2.452)
      (stroke (width 0.15) (type solid)) (layer "F.Fab"))
    (fp_line (start -1.95 2.45) (end -1.95 -1.18)
      (stroke (width 0.15) (type solid)) (layer "F.Fab"))
    (fp_line (start -0.683 -2.452) (end 1.949 -2.452)
      (stroke (width 0.15) (type solid)) (layer "F.Fab"))
    (fp_line (start 1.949 -2.452) (end 1.949 2.45)
      (stroke (width 0.15) (type solid)) (layer "F.Fab"))
    (fp_line (start 1.949 2.45) (end -1.95 2.45)
      (stroke (width 0.15) (type solid)) (layer "F.Fab"))
    (pad "1" smd roundrect (at -2.714 -1.905 270) (size 0.65 1.525) (layers "F.Cu" "F.Paste" "F.Mask") (roundrect_rratio 0.25)
      (net 28 "C_MEAS_3") (pinfunction "IN+") (pintype "input"))
    (pad "2" smd roundrect (at -2.714 -0.635 270) (size 0.65 1.525) (layers "F.Cu" "F.Paste" "F.Mask") (roundrect_rratio 0.25)
      (net 28 "C_MEAS_3") (pinfunction "IN+") (pintype "input"))
    (pad "3" smd roundrect (at -2.714 0.632 270) (size 0.65 1.525) (layers "F.Cu" "F.Paste" "F.Mask") (roundrect_rratio 0.25)
      (net 42 "LOAD_3") (pinfunction "IN-") (pintype "input"))
    (pad "4" smd roundrect (at -2.714 1.902 270) (size 0.65 1.525) (layers "F.Cu" "F.Paste" "F.Mask") (roundrect_rratio 0.25)
      (net 42 "LOAD_3") (pinfunction "IN-") (pintype "input"))
    (pad "5" smd roundrect (at 2.712 1.902 270) (size 0.65 1.525) (layers "F.Cu" "F.Paste" "F.Mask") (roundrect_rratio 0.25)
      (net 4 "GND") (pinfunction "GND") (pintype "power_in"))
    (pad "6" smd roundrect (at 2.712 0.632 270) (size 0.65 1.525) (layers "F.Cu" "F.Paste" "F.Mask") (roundrect_rratio 0.25)
      (net 4 "GND") (pinfunction "VREF") (pintype "input"))
    (pad "7" smd roundrect (at 2.712 -0.635 270) (size 0.65 1.525) (layers "F.Cu" "F.Paste" "F.Mask") (roundrect_rratio 0.25)
      (net 48 "/Power Cycling & Current Measurement/C_ADC3") (pinfunction "VOUT") (pintype "output"))
    (pad "8" smd roundrect (at 2.712 -1.905 270) (size 0.65 1.525) (layers "F.Cu" "F.Paste" "F.Mask") (roundrect_rratio 0.25)
      (net 1 "VCC3V3") (pinfunction "VCC") (pintype "power_in"))
  )
	(footprint "antmicro-footprints:R_0402_1005Metric" (layer "F.Cu")
    (at 170.15 96.5 90)
    (descr "Resistor SMD 0402")
    (tags "resistor SMD 0402")
    (property "Author" "Antmicro")
    (property "Current" "1A")
    (property "DNP" "DNP")
    (property "License" "Apache-2.0")
    (property "MPN" "ERJ2GE0R00X")
    (property "Manufacturer" "Panasonic")
    (property "Sheetfile" "pow-cycl-curr-meas.kicad_sch")
    (property "Sheetname" "Power Cycling & Current Measurement")
    (property "Tolerance" "")
    (property "Val" "0R")
    (property "dnp" "")
    (property "exclude_from_bom" "")
    (property "ki_description" "SMD Chip Resistor, Jumper, 0 ohm, 100 mW, 0402 [1005 Metric], Thick Film, General Purpose")
    (property "ki_keywords" "0402, SMT, RESISTOR, PASSIVE")
    (attr smd exclude_from_bom)
    (fp_text reference "R17" (at 0.85 0.45 90) (layer "F.SilkS")
        (effects (font (size 0.7 0.7) (thickness 0.15)) (justify left bottom))
    )
    (fp_text value "R_0R_0402" (at -1.011843 1.772047 90) (layer "F.Fab")
        (effects (font (size 0.7 0.7) (thickness 0.15)) (justify left bottom))
    )
    (fp_text user "Author: Antmicro" (at -0.95 4.169 90) (layer "F.Fab") hide
        (effects (font (size 0.7 0.7) (thickness 0.15)) (justify left bottom))
    )
    (fp_text user "License: Apache-2.0" (at -0.95 5.169 90) (layer "F.Fab") hide
        (effects (font (size 0.7 0.7) (thickness 0.15)) (justify left bottom))
    )
    (fp_text user "${REFERENCE}" (at -0.95 3.168 90) (layer "F.Fab") hide
        (effects (font (size 0.7 0.7) (thickness 0.15)) (justify left bottom))
    )
    (fp_rect (start -0.925 -0.47) (end 0.925 0.47)
      (stroke (width 0.05) (type default)) (fill none) (layer "F.CrtYd"))
    (fp_rect (start -0.5 -0.25) (end 0.5 0.25)
      (stroke (width 0.15) (type solid)) (fill none) (layer "F.Fab"))
    (pad "1" smd roundrect (at -0.48 0 90) (size 0.59 0.64) (layers "F.Cu" "F.Paste" "F.Mask") (roundrect_rratio 0.25)
      (net 1 "VCC3V3") (pintype "passive"))
    (pad "2" smd roundrect (at 0.48 0 90) (size 0.59 0.64) (layers "F.Cu" "F.Paste" "F.Mask") (roundrect_rratio 0.25)
      (net 107 "Net-(U10-A2)") (pintype "passive"))
  )
	(footprint "antmicro-footprints:MOLEX_39288080" (layer "F.Cu")
    (at 145.25 74.7 90)
    (property "Author" "Antmicro")
    (property "License" "Apache-2.0")
    (property "MPN" "39-28-8080")
    (property "Manufacturer" "Molex")
    (property "Sheetfile" "d1600e-psu-breakout-board.kicad_sch")
    (property "Sheetname" "")
    (property "ki_description" "Pin Header, THT, Vertical, UL94V-2, Power, Wire-to-Board, 4.2 mm, 2 Rows, 8 Contacts, Mini-fit Jr, 5566 series")
    (property "ki_keywords" "VERTICAL, THT, HEADER, CONNECTOR, MALE, WIRE-BOARD, POWER")
    (attr through_hole)
    (fp_text reference "J5" (at -2 -2.7 90) (layer "F.SilkS")
        (effects (font (size 0.7 0.7) (thickness 0.15)) (justify left bottom))
    )
    (fp_text value "Molex_Mini-Fit-Jr_2x4_39-28-8080" (at 4.49 11.365 90) (layer "F.Fab")
        (effects (font (size 0.7 0.7) (thickness 0.15)) (justify left bottom))
    )
    (fp_text user "License: Apache-2.0" (at -3.5 14.565 90) (layer "F.Fab") hide
        (effects (font (size 0.7 0.7) (thickness 0.15)) (justify left bottom))
    )
    (fp_text user "PTH D1.40 +/- 0.05" (at -3.5 13.365 90) (layer "F.Fab") hide
        (effects (font (size 0.7 0.7) (thickness 0.15)) (justify left bottom))
    )
    (fp_text user "Author: Antmicro" (at -3.5 16.965 90) (layer "F.Fab") hide
        (effects (font (size 0.7 0.7) (thickness 0.15)) (justify left bottom))
    )
    (fp_text user "${REFERENCE}" (at -3.5 15.765 90) (layer "F.Fab") hide
        (effects (font (size 0.7 0.7) (thickness 0.15)) (justify left bottom))
    )
    (fp_line (start -3.1 8.75) (end -3.1 -0.98)
      (stroke (width 0.15) (type solid)) (layer "F.SilkS"))
    (fp_line (start -1.83 -2.25) (end -3.1 -0.98)
      (stroke (width 0.15) (type solid)) (layer "F.SilkS"))
    (fp_line (start -1.83 -2.25) (end 15.7 -2.25)
      (stroke (width 0.15) (type solid)) (layer "F.SilkS"))
    (fp_line (start -0.4 -3.327) (end 0 -2.627)
      (stroke (width 0.15) (type solid)) (layer "F.SilkS"))
    (fp_line (start 0 -2.627) (end 0.4 -3.327)
      (stroke (width 0.15) (type solid)) (layer "F.SilkS"))
    (fp_line (start 0.4 -3.327) (end -0.4 -3.327)
      (stroke (width 0.15) (type solid)) (layer "F.SilkS"))
    (fp_line (start 15.7 -2.25) (end 15.7 8.75)
      (stroke (width 0.15) (type solid)) (layer "F.SilkS"))
    (fp_line (start 15.7 8.75) (end -3.1 8.75)
      (stroke (width 0.15) (type solid)) (layer "F.SilkS"))
    (fp_circle (center 0 -3) (end 0.05 -3)
      (stroke (width 0.15) (type solid)) (fill solid) (layer "F.SilkS"))
    (fp_circle (center 0 5.5) (end 0.513 5.5)
      (stroke (width 1.0262) (type solid)) (fill none) (layer "B.Mask"))
    (fp_circle (center 4.2 0) (end 4.713 0)
      (stroke (width 1.0262) (type solid)) (fill none) (layer "B.Mask"))
    (fp_circle (center 4.2 5.5) (end 4.713 5.5)
      (stroke (width 1.0262) (type solid)) (fill none) (layer "B.Mask"))
    (fp_circle (center 8.4 0) (end 8.913 0)
      (stroke (width 1.0262) (type solid)) (fill none) (layer "B.Mask"))
    (fp_circle (center 8.4 5.5) (end 8.913 5.5)
      (stroke (width 1.0262) (type solid)) (fill none) (layer "B.Mask"))
    (fp_circle (center 12.6 0) (end 13.113 0)
      (stroke (width 1.0262) (type solid)) (fill none) (layer "B.Mask"))
    (fp_circle (center 12.6 5.5) (end 13.113 5.5)
      (stroke (width 1.0262) (type solid)) (fill none) (layer "B.Mask"))
    (fp_poly
      (pts
        (xy -1.026 -1.026)
        (xy 1.026 -1.026)
        (xy 1.026 1.026)
        (xy -1.026 1.026)
      )

      (stroke (width 0.01) (type solid)) (fill solid) (layer "B.Mask"))
    (fp_circle (center 0 5.5) (end 0.513 5.5)
      (stroke (width 1.0262) (type solid)) (fill none) (layer "F.Mask"))
    (fp_circle (center 4.2 0) (end 4.713 0)
      (stroke (width 1.0262) (type solid)) (fill none) (layer "F.Mask"))
    (fp_circle (center 4.2 5.5) (end 4.713 5.5)
      (stroke (width 1.0262) (type solid)) (fill none) (layer "F.Mask"))
    (fp_circle (center 8.4 0) (end 8.913 0)
      (stroke (width 1.0262) (type solid)) (fill none) (layer "F.Mask"))
    (fp_circle (center 8.4 5.5) (end 8.913 5.5)
      (stroke (width 1.0262) (type solid)) (fill none) (layer "F.Mask"))
    (fp_circle (center 12.6 0) (end 13.113 0)
      (stroke (width 1.0262) (type solid)) (fill none) (layer "F.Mask"))
    (fp_circle (center 12.6 5.5) (end 13.113 5.5)
      (stroke (width 1.0262) (type solid)) (fill none) (layer "F.Mask"))
    (fp_poly
      (pts
        (xy -1.026 -1.026)
        (xy 1.026 -1.026)
        (xy 1.026 1.026)
        (xy -1.026 1.026)
      )

      (stroke (width 0.01) (type solid)) (fill solid) (layer "F.Mask"))
    (fp_rect (start -3.5 -2.7) (end 16.1 9.1)
      (stroke (width 0.05) (type solid)) (fill none) (layer "F.CrtYd"))
    (fp_line (start -3.1 8.75) (end -3.1 -0.98)
      (stroke (width 0.15) (type solid)) (layer "F.Fab"))
    (fp_line (start -1.83 -2.25) (end -3.1 -0.98)
      (stroke (width 0.15) (type solid)) (layer "F.Fab"))
    (fp_line (start -1.83 -2.25) (end 15.7 -2.25)
      (stroke (width 0.15) (type solid)) (layer "F.Fab"))
    (fp_line (start -0.4 -3.327) (end 0 -2.627)
      (stroke (width 0.15) (type solid)) (layer "F.Fab"))
    (fp_line (start 0 -2.627) (end 0.4 -3.327)
      (stroke (width 0.15) (type solid)) (layer "F.Fab"))
    (fp_line (start 0.4 -3.327) (end -0.4 -3.327)
      (stroke (width 0.15) (type solid)) (layer "F.Fab"))
    (fp_line (start 15.7 -2.25) (end 15.7 8.75)
      (stroke (width 0.15) (type solid)) (layer "F.Fab"))
    (fp_line (start 15.7 8.75) (end -3.1 8.75)
      (stroke (width 0.15) (type solid)) (layer "F.Fab"))
    (pad "1" thru_hole rect (at 0 0 90) (size 1.9 1.9) (drill 1.4) (layers "*.Cu")
      (net 4 "GND") (pinfunction "1") (pintype "bidirectional"))
    (pad "2" thru_hole circle (at 4.2 0 90) (size 1.9 1.9) (drill 1.4) (layers "*.Cu")
      (net 4 "GND") (pinfunction "2") (pintype "bidirectional"))
    (pad "3" thru_hole circle (at 8.4 0 90) (size 1.9 1.9) (drill 1.4) (layers "*.Cu")
      (net 4 "GND") (pinfunction "3") (pintype "bidirectional"))
    (pad "4" thru_hole circle (at 12.6 0 90) (size 1.9 1.9) (drill 1.4) (layers "*.Cu")
      (net 4 "GND") (pinfunction "4") (pintype "bidirectional"))
    (pad "5" thru_hole circle (at 0 5.5 90) (size 1.9 1.9) (drill 1.4) (layers "*.Cu")
      (net 42 "LOAD_3") (pinfunction "5") (pintype "bidirectional"))
    (pad "6" thru_hole circle (at 4.2 5.5 90) (size 1.9 1.9) (drill 1.4) (layers "*.Cu")
      (net 42 "LOAD_3") (pinfunction "6") (pintype "bidirectional"))
    (pad "7" thru_hole circle (at 8.4 5.5 90) (size 1.9 1.9) (drill 1.4) (layers "*.Cu")
      (net 42 "LOAD_3") (pinfunction "7") (pintype "bidirectional"))
    (pad "8" thru_hole circle (at 12.6 5.5 90) (size 1.9 1.9) (drill 1.4) (layers "*.Cu")
      (net 42 "LOAD_3") (pinfunction "8") (pintype "bidirectional"))
  )
)
